G04 ================== begin FILE IDENTIFICATION RECORD ==================*
G04 Layout Name:  12432-1.brd*
G04 Film Name:    DIF_REF_L6*
G04 File Format:  Gerber RS274X*
G04 File Origin:  Cadence Allegro 16.2-S037*
G04 Origin Date:  Wed Oct 17 11:00:18 2012*
G04 *
G04 Layer:  BOARD GEOMETRY/OUTLINE*
G04 Layer:  BOARD GEOMETRY/DIF_REF_L6*
G04 Layer:  BOARD GEOMETRY/PANEL_OUTLINE*
G04 *
G04 Offset:    (0.00 0.00)*
G04 Mirror:    No*
G04 Mode:      Positive*
G04 Rotation:  0*
G04 FullContactRelief:  No*
G04 UndefLineWidth:     6.00*
G04 ================== end FILE IDENTIFICATION RECORD ====================*
%FSLAX35Y35*MOIN*%
%IR0*IPPOS*OFA0.00000B0.00000*MIA0B0*SFA1.00000B1.00000*%
%ADD10C,.01*%
%ADD11C,.004*%
%ADD12C,.006*%
G75*
%LPD*%
G75*
G54D10*
G01X-78740Y15000D02*
G03X-63740Y0I15000J0D01*
G01X-78740Y15000D02*
Y319646D01*
G01X-63740Y334646D02*
G03X-78740Y319646I0J-15000D01*
G01Y908315D02*
G03X-63740Y893315I15000J0D01*
G01X-78740Y908315D02*
Y1304286D01*
G01X-63740Y1319286D02*
G03X-78740Y1304286I0J-15000D01*
G01Y1892953D02*
G03X-63740Y1877953I15000J0D01*
G01X-78740Y1892953D02*
Y1977126D01*
G01X-63740Y1992126D02*
G03X-78740Y1977126I0J-15000D01*
G01X-7874Y0D02*
X-63740D01*
G01X-7874Y334646D02*
X-63740D01*
G01X-7874Y893315D02*
X-63740D01*
G01X-7874Y1319286D02*
X-63740D01*
G01X-7874Y1877953D02*
X-63740D01*
G01X-7874Y1992126D02*
X-63740D01*
G01X-7874Y17253D02*
Y0D01*
G01X0Y17214D02*
G03X-7874I-3937J0D01*
G01Y41772D02*
Y167110D01*
G01Y41772D02*
G03X0I3937J0D01*
G01Y167110D02*
G03X-7874I-3937J0D01*
G01Y191667D02*
Y308383D01*
G01Y191667D02*
G03X0I3937J0D01*
G01Y308383D02*
G03X-7874I-3937J0D01*
G01Y331986D02*
Y334646D01*
G01Y332003D02*
G03X0I3937J0D01*
G01X-7874Y905988D02*
Y893315D01*
G01X0Y905988D02*
G03X-7874I-3937J0D01*
G01Y1106301D02*
Y933234D01*
G01D02*
G03X0I3937J0D01*
G01Y1106301D02*
G03X-7874I-3937J0D01*
G01Y1280567D02*
Y1129921D01*
G01D02*
G03X0I3937J0D01*
G01Y1280567D02*
G03X-7874I-3937J0D01*
G01Y1309889D02*
Y1319286D01*
G01Y1309889D02*
G03X0I3937J0D01*
G01X-7874Y1889223D02*
Y1877953D01*
G01X0Y1889223D02*
G03X-7874I-3937J0D01*
G01X0D02*
G03X-7874I-3937J0D01*
G01Y1912843D02*
Y1962927D01*
G01Y1912843D02*
G03X0I3937J0D01*
G01Y1962927D02*
G03X-7874I-3937J0D01*
G01X0D02*
G03X-7874I-3937J0D01*
G01Y1986547D02*
Y1992126D01*
G01Y1986547D02*
G03X0I3937J0D01*
G01X3937Y0D02*
X1029528D01*
G01X0Y3937D02*
G03X3937Y0I3937J0D01*
G01X0Y409646D02*
Y3937D01*
G01X3937Y413583D02*
X0Y409646D01*
G01X19882Y413583D02*
X3937D01*
G01Y421063D02*
X19882D01*
G01X0Y425000D02*
X3937Y421063D01*
G01X0Y819094D02*
Y425000D01*
G01X3937Y823031D02*
X0Y819094D01*
G01X19882Y823031D02*
X3937D01*
G01Y830512D02*
X19882D01*
G01X0Y834449D02*
X3937Y830512D01*
G01X0Y1393898D02*
Y834449D01*
G01X3937Y1397835D02*
X0Y1393898D01*
G01X19882Y1397835D02*
X3937D01*
G01Y1405315D02*
X19882D01*
G01X0Y1409252D02*
X3937Y1405315D01*
G01X0Y1803346D02*
Y1409252D01*
G01X3937Y1807283D02*
X0Y1803346D01*
G01X19882Y1807283D02*
X3937D01*
G01Y1814764D02*
X19882D01*
G01X0Y1818701D02*
X3937Y1814764D01*
G01X0Y1988189D02*
Y1818701D01*
G01X3937Y1992126D02*
G03X0Y1988189I0J-3937D01*
G01X1029528Y1992126D02*
X3937D01*
G01X19882Y413583D02*
G03Y421063I0J3740D01*
G01Y823031D02*
G03Y830512I0J3741D01*
G01Y1397835D02*
G03Y1405315I0J3740D01*
G01Y1807283D02*
G03Y1814764I0J3740D01*
G01X989744Y1616083D02*
X1015354D01*
G01X989744D02*
G03Y1611870I0J-2107D01*
G01X1015354D02*
X989744D01*
G01X1033465Y3937D02*
Y1424882D01*
G01X1029528Y0D02*
G03X1033465Y3937I0J3937D01*
G01X1041338Y24677D02*
G03X1033464I-3937J0D01*
G01X1041338D02*
G03X1033464I-3937J0D01*
G01Y48297D02*
G03X1041338I3937J0D01*
G01Y217343D02*
G03X1033464I-3937J0D01*
G01X1041338D02*
G03X1033464I-3937J0D01*
G01Y240964D02*
G03X1041338I3937J0D01*
G01X1033464D02*
G03X1041338I3937J0D01*
G01Y445039D02*
G03X1033464I-3937J0D01*
G01X1041338D02*
G03X1033464I-3937J0D01*
G01Y468659D02*
G03X1041338I3937J0D01*
G01X1033464D02*
G03X1041338I3937J0D01*
G01Y697473D02*
G03X1033464I-3937J0D01*
G01X1041338D02*
G03X1033464I-3937J0D01*
G01Y721093D02*
G03X1041338I3937J0D01*
G01X1033464D02*
G03X1041338I3937J0D01*
G01Y996852D02*
G03X1033464I-3937J0D01*
G01X1041338D02*
G03X1033464I-3937J0D01*
G01Y1020472D02*
G03X1041338I3937J0D01*
G01X1033464D02*
G03X1041338I3937J0D01*
G01Y1344060D02*
G03X1033464I-3937J0D01*
G01X1041338D02*
G03X1033464I-3937J0D01*
G01Y1367680D02*
G03X1041338I3937J0D01*
G01X1033464D02*
G03X1041338I3937J0D01*
G01X1033465Y1424882D02*
X1029528Y1428819D01*
G01X1019291Y1433740D02*
Y1607933D01*
G01Y1433740D02*
G03X1024213Y1428819I4921J0D01*
G01X1029528D02*
X1024213D01*
G01X1015354Y1616083D02*
X1019291Y1620020D01*
G01Y1607933D02*
X1015354Y1611870D01*
G01X1019291Y1620020D02*
Y1676496D01*
G01X1029528Y1681417D02*
X1033465Y1685354D01*
G01X1024213Y1681417D02*
G03X1019291Y1676496I-1J-4921D01*
G01X1033465Y1685354D02*
Y1988189D01*
G01X1024213Y1681417D02*
X1029528D01*
G01X1041338Y1739719D02*
G03X1033464I-3937J0D01*
G01X1041338D02*
G03X1033464I-3937J0D01*
G01Y1763339D02*
G03X1041338I3937J0D01*
G01X1033464D02*
G03X1041338I3937J0D01*
G01Y1959242D02*
G03X1033464I-3937J0D01*
G01X1041338D02*
G03X1033464I-3937J0D01*
G01X1033465Y1988189D02*
G03X1029528Y1992126I-3937J0D01*
G01X1033464Y1982862D02*
G03X1041338I3937J0D01*
G01Y24677D02*
Y0D01*
G01D02*
X1097205D01*
G01X1041338Y217343D02*
Y48297D01*
G01Y445039D02*
Y240964D01*
G01Y697473D02*
Y468601D01*
G01Y996852D02*
Y721093D01*
G01Y1344060D02*
Y1020472D01*
G01Y1367680D02*
Y1393701D01*
G01D02*
X1097205D01*
G01X1041338Y1733129D02*
Y1716536D01*
G01X1065043D02*
X1041338D01*
G01Y1739719D02*
Y1731536D01*
G01Y1959242D02*
Y1763310D01*
G01Y1992126D02*
X1097205D01*
G01X1041338Y1982862D02*
Y1992126D01*
G01X1056338Y1716536D02*
X1097205D01*
G01Y0D02*
G03X1112205Y15000I0J15000D01*
G01Y1378701D02*
G03X1097205Y1393701I-15000J0D01*
G01Y1716536D02*
G03X1112205Y1731536I0J15000D01*
G01Y1977126D02*
G03X1097205Y1992126I-15000J0D01*
G01X1112205Y648419D02*
Y15000D01*
G01Y656293D02*
G03Y648419I0J-3937D01*
G01Y1378701D02*
Y656293D01*
G01Y1977126D02*
Y1731536D01*
G54D11*
G01X59999Y537550D02*
X60504Y537044D01*
G01D02*
G03X62099Y536384I1594J1595D01*
G01X60003Y534150D02*
X60074Y534221D01*
G01D02*
G02X62399Y535184I2325J-2325D01*
G01X50300Y699200D02*
G03X52953Y698101I2653J2653D01*
G01D02*
X64429D01*
G01X64428Y696901D02*
X53066D01*
G01D02*
G03X50410Y695801I0J-3756D01*
G01X67042Y1717800D02*
X47751D01*
G01D02*
G02X44251Y1719251I2J4952D01*
G01D02*
X44250Y1719250D01*
G01D02*
X42913Y1720587D01*
G01D02*
G02X41500Y1724001I3413J3412D01*
G01X42700Y1724000D02*
G03X43762Y1721436I3626J0D01*
G01D02*
X45099Y1720099D01*
G01D02*
G03X47752Y1719000I2653J2653D01*
G01D02*
X67041D01*
G01X41500Y1724001D02*
Y1728025D01*
G01D02*
G02X43251Y1732249I5976J-2D01*
G01D02*
X43250Y1732250D01*
G01D02*
X44174Y1733174D01*
G01D02*
G03X44299Y1733477I-303J302D01*
G01D02*
X44300Y1733476D01*
G01D02*
Y1735450D01*
G01D02*
G03X43628Y1737072I-2294J0D01*
G01D02*
X43600Y1737100D01*
G01X47000D02*
X46278Y1736378D01*
G01D02*
G03X45500Y1734500I1878J-1878D01*
G01D02*
Y1733477D01*
G01D02*
G02X45023Y1732325I-1629J0D01*
G01D02*
X44099Y1731401D01*
G01D02*
G03X42700Y1728024I3377J-3377D01*
G01D02*
Y1724000D01*
G01X66292Y1726050D02*
X48839D01*
G01D02*
G03X45877Y1724823I0J-4189D01*
G01Y1728477D02*
G03X48839Y1727250I2962J2962D01*
G01D02*
X66293D01*
G01X62497Y474346D02*
X63494Y473349D01*
G01D02*
G03X64199Y473057I705J705D01*
G01D02*
X69343D01*
G01D02*
G03X71499Y473950I0J3049D01*
G01D02*
X130349Y532800D01*
G01X62503Y470946D02*
X62788Y471231D01*
G01D02*
G02X64299Y471857I1511J-1511D01*
G01D02*
X69345D01*
G01D02*
G03X72348Y473101I0J4247D01*
G01D02*
X131198Y531951D01*
G01X63067Y489616D02*
G03X63978Y488705I911J0D01*
G01D02*
X78819D01*
G01D02*
G03X81523Y489825I0J3824D01*
G01D02*
X110773Y519075D01*
G01X62978Y486217D02*
G02X64266Y487505I1288J0D01*
G01D02*
X78819D01*
G01D02*
G03X82372Y488976I1J5024D01*
G01X62099Y536384D02*
X69999D01*
G01D02*
G02X73181Y535066I0J-4500D01*
G01D02*
X81307Y526940D01*
G01D02*
G03X83456Y526050I2149J2149D01*
G01X62399Y535184D02*
X70044D01*
G01D02*
G02X72299Y534250I0J-3189D01*
G01D02*
X80457Y526092D01*
G01D02*
G03X83455Y524850I2998J2997D01*
G01X64429Y698101D02*
G03X69004Y699996I0J6470D01*
G01D02*
X82408Y713400D01*
G01X83257Y712551D02*
X69853Y699147D01*
G01D02*
X69852Y699148D01*
G01D02*
G02X64428Y696901I-5424J5423D01*
G01X82400Y927800D02*
X80900Y929300D01*
G01D02*
X80901Y929301D01*
G01D02*
G02X79400Y932924I3622J3623D01*
G01D02*
Y939901D01*
G01D02*
G02X80742Y943142I4585J0D01*
G01X81591Y942293D02*
G03X80600Y939900I2394J-2393D01*
G01D02*
Y932923D01*
G01D02*
G03X81749Y930149I3923J0D01*
G01D02*
X83249Y928649D01*
G01X80742Y943142D02*
X82950Y945350D01*
G01X83799Y944501D02*
X81591Y942293D01*
G01X76050Y1724050D02*
X71750Y1719750D01*
G01D02*
X71749Y1719751D01*
G01D02*
G02X67042Y1717800I-4709J4708D01*
G01X67041Y1719000D02*
G03X70901Y1720599I0J5459D01*
G01D02*
X75201Y1724899D01*
G01X121077Y1726100D02*
X81000D01*
G01D02*
G03X76050Y1724050I0J-7001D01*
G01X75201Y1724899D02*
G02X81001Y1727300I5798J-5800D01*
G01D02*
X121078D01*
G01X83990Y1731600D02*
X77500D01*
G01D02*
G03X72550Y1729550I0J-7001D01*
G01D02*
X71000Y1728000D01*
G01D02*
G02X66292Y1726050I-4708J4708D01*
G01X66293Y1727250D02*
G03X70152Y1728848I0J5458D01*
G01D02*
X70151Y1728849D01*
G01D02*
X71701Y1730399D01*
G01D02*
G02X77501Y1732800I5798J-5800D01*
G01D02*
X110085D01*
G01X82372Y488976D02*
X111622Y518226D01*
G01X83456Y526050D02*
X87099D01*
G01D02*
G03X88298Y526546I1J1695D01*
G01D02*
X88800Y527049D01*
G01D02*
X89900Y528149D01*
G01D02*
G03X90299Y529112I-963J963D01*
G01D02*
Y532943D01*
G01D02*
G03X90153Y533296I-500J0D01*
G01D02*
X89845Y533604D01*
G01D02*
G03X89492Y533750I-353J-354D01*
G01D02*
X87023D01*
G01D02*
G03X86299Y533450I0J-1024D01*
G01D02*
X86199Y533350D01*
G01D02*
G03Y532250I550J-550D01*
G01X83455Y524850D02*
X87099D01*
G01D02*
Y524851D01*
G01D02*
G03X89148Y525697I4J2896D01*
G01D02*
X89650Y526201D01*
G01D02*
X90749Y527300D01*
G01D02*
G03X91499Y529111I-1812J1811D01*
G01D02*
Y532943D01*
G01D02*
G03X91003Y534145I-1700J2D01*
G01D02*
X90694Y534454D01*
G01D02*
G03X89492Y534950I-1200J-1204D01*
G01D02*
X87594D01*
G01D02*
G02X87047Y535176I-1J773D01*
G01D02*
X86199Y536025D01*
G01X82408Y713400D02*
G03X83899Y717000I-3601J3600D01*
G01D02*
Y924181D01*
G01X85099Y924180D02*
Y716999D01*
G01D02*
G02X83257Y712551I-6292J0D01*
G01X83899Y924181D02*
G03X82400Y927800I-5118J0D01*
G01X83249Y928649D02*
X83248Y928648D01*
G01D02*
G02X85099Y924180I-4467J-4468D01*
G01X82950Y945350D02*
G03X83700Y947161I-1811J1811D01*
G01D02*
Y971501D01*
G01X84900Y971500D02*
Y947162D01*
G01D02*
G02X83798Y944502I-3761J0D01*
G01D02*
X83799Y944501D01*
G01X83700Y971501D02*
G02X85688Y976301I6789J0D01*
G01D02*
X95743Y986356D01*
G01X96592Y985507D02*
X86537Y975452D01*
G01D02*
G03X84900Y971500I3952J-3952D01*
G01X95743Y986356D02*
G03X97250Y989994I-3638J3638D01*
G01D02*
Y1054126D01*
G01X98450Y1054127D02*
Y989993D01*
G01D02*
G02X96591Y985508I-6345J2D01*
G01D02*
X96592Y985507D01*
G01X97250Y1054126D02*
G02X98751Y1057749I5123J0D01*
G01D02*
X98750Y1057750D01*
G01D02*
X120011Y1079011D01*
G01X120860Y1078162D02*
X99599Y1056901D01*
G01D02*
G03X98450Y1054127I2774J-2774D01*
G01X110086Y1731600D02*
X96590D01*
G01D02*
G03X96290Y1731300I0J-300D01*
G01D02*
G02X95990Y1731000I-300J0D01*
G01D02*
X94190D01*
G01D02*
G02X93890Y1731300I0J300D01*
G01D02*
G03X93590Y1731600I-300J0D01*
G01D02*
X91790D01*
G01D02*
G03X91490Y1731300I0J-300D01*
G01D02*
G02X91190Y1731000I-300J0D01*
G01D02*
X89390D01*
G01D02*
G02X89090Y1731300I0J300D01*
G01D02*
G03X88790Y1731600I-300J0D01*
G01D02*
X86990D01*
G01D02*
G03X86690Y1731300I0J-300D01*
G01D02*
G02X86390Y1731000I-300J0D01*
G01D02*
X84590D01*
G01D02*
G02X84290Y1731300I0J300D01*
G01D02*
G03X83990Y1731600I-300J0D01*
G01X110773Y519075D02*
G03X111623Y521127I-2052J2052D01*
G01D02*
Y625569D01*
G01X111622Y518226D02*
G03X112823Y521126I-2901J2900D01*
G01D02*
Y625569D01*
G01X130177Y584350D02*
X123099D01*
G01D02*
G02X119299Y588150I0J3800D01*
G01D02*
Y623230D01*
G01X130178Y585550D02*
X123099D01*
G01D02*
G02X120499Y588150I0J2600D01*
G01D02*
Y617376D01*
G01X119299Y623230D02*
G02X121150Y627699I6321J0D01*
G01X120499Y617376D02*
G02X120699Y617576I200J0D01*
G01D02*
G03X120899Y617776I0J200D01*
G01D02*
Y619776D01*
G01D02*
G03X120699Y619976I-200J0D01*
G01D02*
G02X120499Y620176I0J200D01*
G01D02*
Y623229D01*
G01D02*
G02X121999Y626850I5121J0D01*
G01X111623Y625569D02*
G02X113250Y629499I5557J1D01*
G01D02*
X120098Y636347D01*
G01D02*
X120312Y636562D01*
G01D02*
G02X122699Y637549I2384J-2386D01*
G01D02*
Y637550D01*
G01D02*
X123799D01*
G01D02*
G03X124311Y637762I0J724D01*
G01D02*
X125499Y638950D01*
G01X112823Y625569D02*
G02X114099Y628650I4357J0D01*
G01D02*
X120949Y635500D01*
G01D02*
X121162Y635714D01*
G01D02*
G02X122699Y636350I1536J-1537D01*
G01D02*
X123799D01*
G01D02*
G02X125336Y635714I1J-2173D01*
G01X121150Y627699D02*
G02X123449Y628650I2297J-2298D01*
G01D02*
X130667D01*
G01X121999Y626850D02*
G02X123448Y627450I1449J-1449D01*
G01D02*
X130668D01*
G01X120011Y1079011D02*
G02X122399Y1080000I2388J-2389D01*
G01D02*
X122400D01*
G01D02*
G03X123844Y1080598I0J2042D01*
G01D02*
X124423Y1081177D01*
G01Y1077523D02*
X123673Y1078272D01*
G01D02*
G03X122400Y1078800I-1274J-1273D01*
G01D02*
G03X120860Y1078162I0J-2178D01*
G01X113500Y1348154D02*
G03X116462Y1346927I2962J2962D01*
G01D02*
X129410D01*
G01X129411Y1345727D02*
X116462D01*
G01D02*
G03X113500Y1344500I0J-4189D01*
G01X126750Y1723750D02*
G03X121077Y1726100I-5673J-5673D01*
G01X121078Y1727300D02*
G02X127598Y1724598I-2J-9223D01*
G01X183442Y1740499D02*
X122307D01*
G01D02*
G03X119403Y1739296I0J-4107D01*
G01D02*
X112853Y1732746D01*
G01D02*
X112852Y1732747D01*
G01D02*
G02X110086Y1731600I-2768J2767D01*
G01X110085Y1732800D02*
G03X112004Y1733595I0J2714D01*
G01D02*
X118554Y1740145D01*
G01D02*
X118555Y1740144D01*
G01D02*
G02X122306Y1741699I3753J-3752D01*
G01D02*
X183443D01*
G01X130349Y532800D02*
X132777Y535227D01*
G01D02*
G03X134898Y540350I-5124J5122D01*
G01X131198Y531951D02*
X133626Y534378D01*
G01D02*
G03X136099Y540350I-5972J5971D01*
G01X134898D02*
X134899Y540349D01*
G01D02*
Y578498D01*
G01X136099Y540350D02*
Y578497D01*
G01X134899Y578498D02*
X134898Y578497D01*
G01D02*
G03X132950Y583201I-6652J0D01*
G01X136099Y578497D02*
G03X133799Y584050I-7853J0D01*
G01X132950Y583201D02*
G03X130177Y584350I-2773J-2772D01*
G01X133799Y584050D02*
G03X130178Y585550I-3621J-3621D01*
G01X125336Y635714D02*
X125499Y635550D01*
G01X130667Y628650D02*
G03X131750Y629099I0J1531D01*
G01D02*
G03X132399Y630665I-1565J1566D01*
G01D02*
Y639534D01*
G01D02*
G02X133399Y641950I3416J1D01*
G01D02*
X137999Y646550D01*
G01X130668Y627450D02*
G03X132599Y628250I0J2731D01*
G01D02*
G03X133599Y630664I-2414J2414D01*
G01D02*
Y639534D01*
G01D02*
G02X134248Y641101I2216J0D01*
G01D02*
X138848Y645701D01*
G01X137999Y646550D02*
G02X140415Y647550I2415J-2416D01*
G01D02*
X142657D01*
G01D02*
G03X144238Y649131I0J1581D01*
G01X138848Y645701D02*
G02X140415Y646350I1567J-1567D01*
G01D02*
X143244D01*
G01D02*
G02X144238Y645356I0J-994D01*
G01X137477Y1081177D02*
G03X140393Y1079969I2916J2916D01*
G01D02*
X146000D01*
G01X146001Y1078769D02*
X140407D01*
G01D02*
G03X137481Y1077557I0J-4138D01*
G01X129410Y1346927D02*
G03X132000Y1348000I0J3663D01*
G01D02*
X132487Y1348487D01*
G01D02*
G03X134149Y1352500I-4014J4013D01*
G01D02*
Y1367874D01*
G01X135349Y1556000D02*
Y1352499D01*
G01D02*
G02X133336Y1347638I-6876J0D01*
G01D02*
X132849Y1347151D01*
G01D02*
G02X129411Y1345727I-3438J3439D01*
G01X134149Y1367874D02*
G03X133825Y1368198I-324J0D01*
G01D02*
X133824D01*
G01D02*
G02X133500Y1368522I0J324D01*
G01D02*
Y1370274D01*
G01D02*
G02X133824Y1370598I324J0D01*
G01D02*
X133825D01*
G01D02*
G03X134149Y1370922I0J324D01*
G01D02*
Y1372674D01*
G01D02*
G03X133825Y1372998I-324J0D01*
G01D02*
X133824D01*
G01D02*
G02X133500Y1373322I0J324D01*
G01D02*
Y1375074D01*
G01D02*
G02X133824Y1375398I324J0D01*
G01D02*
X133825D01*
G01D02*
G03X134149Y1375722I0J324D01*
G01D02*
Y1533970D01*
G01D02*
G03X133825Y1534294I-324J0D01*
G01D02*
X133824D01*
G01D02*
G02X133500Y1534618I0J324D01*
G01D02*
Y1536370D01*
G01D02*
G02X133824Y1536694I324J0D01*
G01D02*
X133825D01*
G01D02*
G03X134149Y1537018I0J324D01*
G01D02*
Y1538770D01*
G01D02*
G03X133825Y1539094I-324J0D01*
G01D02*
X133824D01*
G01D02*
G02X133500Y1539418I0J324D01*
G01D02*
Y1541170D01*
G01D02*
G02X133824Y1541494I324J0D01*
G01D02*
X133825D01*
G01D02*
G03X134149Y1541818I0J324D01*
G01D02*
Y1543570D01*
G01D02*
G03X133825Y1543894I-324J0D01*
G01D02*
X133824D01*
G01D02*
G02X133500Y1544218I0J324D01*
G01D02*
Y1545970D01*
G01D02*
G02X133824Y1546294I324J0D01*
G01D02*
X133825D01*
G01D02*
G03X134149Y1546618I0J324D01*
G01D02*
Y1555999D01*
G01D02*
G02X137435Y1563935I11221J2D01*
G01D02*
X164172Y1590672D01*
G01X165021Y1589823D02*
X138284Y1563086D01*
G01D02*
G03X135349Y1556000I7086J-7086D01*
G01X146000Y1701199D02*
G03X143666Y1706834I-7969J0D01*
G01D02*
X126750Y1723750D01*
G01X127599Y1724599D02*
X144515Y1707683D01*
G01D02*
G02X147200Y1701198I-6484J-6483D01*
G01X127598Y1724598D02*
X127599Y1724599D01*
G01X146000Y1079969D02*
G03X149361Y1081361I0J4754D01*
G01D02*
X187450Y1119450D01*
G01X188299Y1118601D02*
X150210Y1080512D01*
G01D02*
G02X146001Y1078769I-4209J4211D01*
G01X164172Y1590672D02*
G03X167000Y1597500I-6829J6828D01*
G01X168200Y1597499D02*
G02X165021Y1589823I-10857J0D01*
G01X167000Y1651172D02*
G03X165000Y1656000I-6828J0D01*
G01D02*
X148250Y1672750D01*
G01X149099Y1673599D02*
X165849Y1656849D01*
G01D02*
X165848Y1656848D01*
G01D02*
G02X168200Y1651173I-5676J-5677D01*
G01X148250Y1672750D02*
X148251Y1672751D01*
G01D02*
G02X146000Y1678185I5433J5434D01*
G01D02*
Y1701199D01*
G01X147200Y1701198D02*
Y1678184D01*
G01D02*
G03X149099Y1673599I6484J0D01*
G01X187450Y1119450D02*
G03X189074Y1123371I-3921J3921D01*
G01X167000Y1597500D02*
Y1651172D01*
G01X168200Y1651173D02*
Y1597499D01*
G01X188145Y1737145D02*
X185745Y1739545D01*
G01D02*
G03X183442Y1740499I-2303J-2303D01*
G01X183443Y1741699D02*
G02X186593Y1740393I-2J-4457D01*
G01D02*
X186594Y1740394D01*
G01D02*
X188994Y1737994D01*
G01X189074Y1123371D02*
Y1327764D01*
G01X190274Y1734902D02*
Y1123372D01*
G01D02*
G02X188298Y1118602I-6745J0D01*
G01D02*
X188299Y1118601D01*
G01X189074Y1327764D02*
G03X188787Y1328051I-287J0D01*
G01D02*
G02X188500Y1328338I0J287D01*
G01D02*
Y1330164D01*
G01D02*
G02X188787Y1330451I287J0D01*
G01D02*
G03X189074Y1330738I0J287D01*
G01D02*
Y1332564D01*
G01D02*
G03X188787Y1332851I-287J0D01*
G01D02*
G02X188500Y1333138I0J287D01*
G01D02*
Y1334964D01*
G01D02*
G02X188787Y1335251I287J0D01*
G01D02*
G03X189074Y1335538I0J287D01*
G01D02*
Y1603283D01*
G01D02*
G03X188787Y1603570I-287J0D01*
G01D02*
G02X188500Y1603857I0J287D01*
G01D02*
Y1605683D01*
G01D02*
G02X188787Y1605970I287J0D01*
G01D02*
G03X189074Y1606257I0J287D01*
G01D02*
Y1608083D01*
G01D02*
G03X188787Y1608370I-287J0D01*
G01D02*
G02X188500Y1608657I0J287D01*
G01D02*
Y1610483D01*
G01D02*
G02X188787Y1610770I287J0D01*
G01D02*
G03X189074Y1611057I0J287D01*
G01D02*
Y1734902D01*
G01D02*
G03X188145Y1737145I-3172J0D01*
G01X188994Y1737994D02*
G02X190274Y1734902I-3092J-3091D01*
G54D12*
G01X1019291Y1620020D02*
Y1676496D01*
G02X1024213Y1681417I4921J0D01*
G01X1029528D01*
X1033465Y1685354D01*
Y1988189D01*
G03X1029528Y1992126I-3937J0D01*
G01X3937D01*
G03X0Y1988189I0J-3937D01*
G01Y1818701D01*
X3937Y1814764D01*
X19882D01*
G02Y1807283I0J-3740D01*
G01X3937D01*
X0Y1803346D01*
Y1409252D01*
X3937Y1405315D01*
X19882D01*
G02Y1397835I0J-3740D01*
G01X3937D01*
X0Y1393898D01*
Y834449D01*
X3937Y830512D01*
X19882D01*
G02Y823031I0J-3740D01*
G01X3937D01*
X0Y819094D01*
Y425000D01*
X3937Y421063D01*
X19882D01*
G02Y413583I0J-3740D01*
G01X3937D01*
X0Y409646D01*
Y3937D01*
G03X3937Y0I3937J0D01*
G01X1029528D01*
G03X1033465Y3937I0J3937D01*
G01Y1424882D01*
X1029528Y1428819D01*
X1024213D01*
G02X1019291Y1433740I-1J4921D01*
G01Y1607933D01*
X1015354Y1611870D01*
X989744D01*
G02Y1616083I0J2107D01*
G01X1015354D01*
X1019291Y1620020D01*
G01X24705Y1903150D02*
G02X10728I-6989J0D01*
G02X24705I6988J0D01*
G01X30639Y-130979D02*
Y-142979D01*
G01X28339Y-130979D02*
X32939D01*
G01X34939Y-142979D02*
Y-130979D01*
G01Y-136779D02*
X35439Y-135779D01*
X35939Y-135179D01*
X36739Y-134979D01*
X37339Y-135179D01*
X38039Y-135979D01*
X38339Y-137179D01*
Y-142979D01*
G01X42639Y-134979D02*
Y-142979D01*
G01Y-131779D02*
X42439Y-131579D01*
Y-131179D01*
X42639Y-130979D01*
X42839Y-131179D01*
Y-131579D01*
X42639Y-131779D01*
G01X47139Y-141579D02*
X47639Y-142379D01*
X48339Y-142979D01*
X48939D01*
X49539Y-142579D01*
X49939Y-141979D01*
X50139Y-141179D01*
X50039Y-139979D01*
X49639Y-139379D01*
X47839Y-138179D01*
X47439Y-136779D01*
X47639Y-135779D01*
X48039Y-135179D01*
X48639Y-134979D01*
X49239Y-135179D01*
X49839Y-135779D01*
G01X59239Y-145979D02*
X59939Y-146779D01*
X60739Y-146979D01*
X61439Y-146779D01*
X62039Y-145779D01*
X62439Y-144379D01*
Y-134979D01*
G01Y-136579D02*
X62039Y-135779D01*
X61439Y-135179D01*
X60739Y-134979D01*
X59939Y-135379D01*
X59439Y-136179D01*
X59039Y-137579D01*
X58839Y-138979D01*
X58939Y-140179D01*
X59339Y-141579D01*
X59939Y-142579D01*
X60739Y-142979D01*
X61339Y-142779D01*
X62039Y-141979D01*
X62439Y-141179D01*
G01X65139Y-137579D02*
X68339D01*
X68039Y-136179D01*
X67539Y-135379D01*
X66839Y-134979D01*
X66139Y-135179D01*
X65539Y-135779D01*
X65139Y-137179D01*
X64939Y-138379D01*
Y-139579D01*
X65139Y-140779D01*
X65639Y-141979D01*
X66239Y-142779D01*
X66939Y-142979D01*
X67639Y-142579D01*
X68339Y-141379D01*
G01X71239Y-142979D02*
Y-134979D01*
G01Y-136579D02*
X71739Y-135779D01*
X72239Y-135179D01*
X72939Y-134979D01*
X73439Y-135179D01*
X74039Y-135779D01*
G01X76839Y-142979D02*
Y-130979D01*
G01Y-136979D02*
X77339Y-135779D01*
X77939Y-135179D01*
X78539Y-134979D01*
X79439Y-135379D01*
X80039Y-136179D01*
X80439Y-137579D01*
Y-139179D01*
X80239Y-140779D01*
X79839Y-141979D01*
X79139Y-142779D01*
X78539Y-142979D01*
X77939Y-142779D01*
X77339Y-142179D01*
X76839Y-141179D01*
G01X83139Y-137579D02*
X86339D01*
X86039Y-136179D01*
X85539Y-135379D01*
X84839Y-134979D01*
X84139Y-135179D01*
X83539Y-135779D01*
X83139Y-137179D01*
X82939Y-138379D01*
Y-139579D01*
X83139Y-140779D01*
X83639Y-141979D01*
X84239Y-142779D01*
X84939Y-142979D01*
X85639Y-142579D01*
X86339Y-141379D01*
G01X89239Y-142979D02*
Y-134979D01*
G01Y-136579D02*
X89739Y-135779D01*
X90239Y-135179D01*
X90939Y-134979D01*
X91439Y-135179D01*
X92039Y-135779D01*
G01X102639Y-134979D02*
Y-142979D01*
G01Y-131779D02*
X102439Y-131579D01*
Y-131179D01*
X102639Y-130979D01*
X102839Y-131179D01*
Y-131579D01*
X102639Y-131779D01*
G01X107139Y-141579D02*
X107639Y-142379D01*
X108339Y-142979D01*
X108939D01*
X109539Y-142579D01*
X109939Y-141979D01*
X110139Y-141179D01*
X110039Y-139979D01*
X109639Y-139379D01*
X107839Y-138179D01*
X107439Y-136779D01*
X107639Y-135779D01*
X108039Y-135179D01*
X108639Y-134979D01*
X109239Y-135179D01*
X109839Y-135779D01*
G01X119039Y-145979D02*
X119739Y-146779D01*
X120339Y-146979D01*
X121139Y-146579D01*
X121739Y-145579D01*
X122039Y-143779D01*
Y-134979D01*
G01Y-131779D02*
X121839Y-131579D01*
Y-131179D01*
X122039Y-130979D01*
X122239Y-131179D01*
Y-131579D01*
X122039Y-131779D01*
G01X124939Y-134979D02*
Y-140579D01*
X125339Y-141979D01*
X125939Y-142779D01*
X126639Y-142979D01*
X127339Y-142779D01*
X127939Y-141979D01*
X128339Y-140579D01*
G01Y-142979D02*
Y-134979D01*
G01X131139Y-141579D02*
X131639Y-142379D01*
X132339Y-142979D01*
X132939D01*
X133539Y-142579D01*
X133939Y-141979D01*
X134139Y-141179D01*
X134039Y-139979D01*
X133639Y-139379D01*
X131839Y-138179D01*
X131439Y-136779D01*
X131639Y-135779D01*
X132039Y-135179D01*
X132639Y-134979D01*
X133239Y-135179D01*
X133839Y-135779D01*
G01X138639Y-130979D02*
Y-142979D01*
G01X137239Y-134979D02*
X140039D01*
G01X150039Y-142979D02*
Y-132779D01*
X150239Y-131779D01*
X150639Y-131179D01*
X151239Y-130979D01*
X151839Y-131379D01*
X152139Y-132379D01*
G01X150939Y-135779D02*
X148939D01*
G01X156639Y-142979D02*
X156039Y-142779D01*
X155439Y-141979D01*
X155039Y-140579D01*
X154839Y-138979D01*
X155039Y-137379D01*
X155439Y-135979D01*
X156039Y-135179D01*
X156639Y-134979D01*
X157239Y-135179D01*
X157839Y-135979D01*
X158239Y-137379D01*
X158339Y-138979D01*
X158239Y-140579D01*
X157839Y-141979D01*
X157239Y-142779D01*
X156639Y-142979D01*
G01X161239D02*
Y-134979D01*
G01Y-136579D02*
X161739Y-135779D01*
X162239Y-135179D01*
X162939Y-134979D01*
X163439Y-135179D01*
X164039Y-135779D01*
G01X172539Y-146579D02*
X173139Y-146979D01*
X173939Y-146579D01*
X174439Y-145779D01*
X174839Y-144779D01*
X175439Y-141579D01*
X176739Y-134979D01*
G01X173539D02*
X175439Y-141579D01*
G01X180639Y-142979D02*
X180039Y-142779D01*
X179439Y-141979D01*
X179039Y-140579D01*
X178839Y-138979D01*
X179039Y-137379D01*
X179439Y-135979D01*
X180039Y-135179D01*
X180639Y-134979D01*
X181239Y-135179D01*
X181839Y-135979D01*
X182239Y-137379D01*
X182339Y-138979D01*
X182239Y-140579D01*
X181839Y-141979D01*
X181239Y-142779D01*
X180639Y-142979D01*
G01X184939Y-134979D02*
Y-140579D01*
X185339Y-141979D01*
X185939Y-142779D01*
X186639Y-142979D01*
X187339Y-142779D01*
X187939Y-141979D01*
X188339Y-140579D01*
G01Y-142979D02*
Y-134979D01*
G01X197239Y-142979D02*
Y-134979D01*
G01Y-136579D02*
X197739Y-135779D01*
X198239Y-135179D01*
X198939Y-134979D01*
X199439Y-135179D01*
X200039Y-135779D01*
G01X203139Y-137579D02*
X206339D01*
X206039Y-136179D01*
X205539Y-135379D01*
X204839Y-134979D01*
X204139Y-135179D01*
X203539Y-135779D01*
X203139Y-137179D01*
X202939Y-138379D01*
Y-139579D01*
X203139Y-140779D01*
X203639Y-141979D01*
X204239Y-142779D01*
X204939Y-142979D01*
X205639Y-142579D01*
X206339Y-141379D01*
G01X210039Y-142979D02*
Y-132779D01*
X210239Y-131779D01*
X210639Y-131179D01*
X211239Y-130979D01*
X211839Y-131379D01*
X212139Y-132379D01*
G01X210939Y-135779D02*
X208939D01*
G01X215139Y-137579D02*
X218339D01*
X218039Y-136179D01*
X217539Y-135379D01*
X216839Y-134979D01*
X216139Y-135179D01*
X215539Y-135779D01*
X215139Y-137179D01*
X214939Y-138379D01*
Y-139579D01*
X215139Y-140779D01*
X215639Y-141979D01*
X216239Y-142779D01*
X216939Y-142979D01*
X217639Y-142579D01*
X218339Y-141379D01*
G01X221239Y-142979D02*
Y-134979D01*
G01Y-136579D02*
X221739Y-135779D01*
X222239Y-135179D01*
X222939Y-134979D01*
X223439Y-135179D01*
X224039Y-135779D01*
G01X227139Y-137579D02*
X230339D01*
X230039Y-136179D01*
X229539Y-135379D01*
X228839Y-134979D01*
X228139Y-135179D01*
X227539Y-135779D01*
X227139Y-137179D01*
X226939Y-138379D01*
Y-139579D01*
X227139Y-140779D01*
X227639Y-141979D01*
X228239Y-142779D01*
X228939Y-142979D01*
X229639Y-142579D01*
X230339Y-141379D01*
G01X232939Y-142979D02*
Y-134979D01*
G01Y-136979D02*
X233339Y-135979D01*
X233939Y-135179D01*
X234739Y-134979D01*
X235439Y-135179D01*
X236039Y-135979D01*
X236339Y-137379D01*
Y-142979D01*
G01X242239Y-135979D02*
X241539Y-135179D01*
X240939Y-134979D01*
X240139Y-135379D01*
X239539Y-136179D01*
X239139Y-137579D01*
X239039Y-138979D01*
X239139Y-140379D01*
X239539Y-141579D01*
X240139Y-142579D01*
X240939Y-142979D01*
X241639Y-142579D01*
X242239Y-141779D01*
G01X245139Y-137579D02*
X248339D01*
X248039Y-136179D01*
X247539Y-135379D01*
X246839Y-134979D01*
X246139Y-135179D01*
X245539Y-135779D01*
X245139Y-137179D01*
X244939Y-138379D01*
Y-139579D01*
X245139Y-140779D01*
X245639Y-141979D01*
X246239Y-142779D01*
X246939Y-142979D01*
X247639Y-142579D01*
X248339Y-141379D01*
G01X258639Y-130979D02*
Y-142979D01*
G01X257239Y-134979D02*
X260039D01*
G01X264639Y-142979D02*
X264039Y-142779D01*
X263439Y-141979D01*
X263039Y-140579D01*
X262839Y-138979D01*
X263039Y-137379D01*
X263439Y-135979D01*
X264039Y-135179D01*
X264639Y-134979D01*
X265239Y-135179D01*
X265839Y-135979D01*
X266239Y-137379D01*
X266339Y-138979D01*
X266239Y-140579D01*
X265839Y-141979D01*
X265239Y-142779D01*
X264639Y-142979D01*
G01X276039D02*
Y-132779D01*
X276239Y-131779D01*
X276639Y-131179D01*
X277239Y-130979D01*
X277839Y-131379D01*
X278139Y-132379D01*
G01X276939Y-135779D02*
X274939D01*
G01X282639Y-134979D02*
Y-142979D01*
G01Y-131779D02*
X282439Y-131579D01*
Y-131179D01*
X282639Y-130979D01*
X282839Y-131179D01*
Y-131579D01*
X282639Y-131779D01*
G01X286939Y-142979D02*
Y-134979D01*
G01Y-136979D02*
X287339Y-135979D01*
X287939Y-135179D01*
X288739Y-134979D01*
X289439Y-135179D01*
X290039Y-135979D01*
X290339Y-137379D01*
Y-142979D01*
G01X296439Y-130979D02*
Y-142979D01*
G01Y-141179D02*
X296039Y-142179D01*
X295439Y-142779D01*
X294739Y-142979D01*
X293939Y-142579D01*
X293339Y-141579D01*
X292939Y-140379D01*
X292839Y-138979D01*
X292939Y-137579D01*
X293339Y-136379D01*
X293939Y-135379D01*
X294739Y-134979D01*
X295439Y-135179D01*
X295939Y-135579D01*
X296439Y-136379D01*
G01X306639Y-130979D02*
Y-142979D01*
G01X305239Y-134979D02*
X308039D01*
G01X310939Y-142979D02*
Y-130979D01*
G01Y-136779D02*
X311439Y-135779D01*
X311939Y-135179D01*
X312739Y-134979D01*
X313339Y-135179D01*
X314039Y-135979D01*
X314339Y-137179D01*
Y-142979D01*
G01X317139Y-137579D02*
X320339D01*
X320039Y-136179D01*
X319539Y-135379D01*
X318839Y-134979D01*
X318139Y-135179D01*
X317539Y-135779D01*
X317139Y-137179D01*
X316939Y-138379D01*
Y-139579D01*
X317139Y-140779D01*
X317639Y-141979D01*
X318239Y-142779D01*
X318939Y-142979D01*
X319639Y-142579D01*
X320339Y-141379D01*
G01X332439Y-130979D02*
Y-142979D01*
G01Y-141179D02*
X332039Y-142179D01*
X331439Y-142779D01*
X330739Y-142979D01*
X329939Y-142579D01*
X329339Y-141579D01*
X328939Y-140379D01*
X328839Y-138979D01*
X328939Y-137579D01*
X329339Y-136379D01*
X329939Y-135379D01*
X330739Y-134979D01*
X331439Y-135179D01*
X331939Y-135579D01*
X332439Y-136379D01*
G01X336639Y-134979D02*
Y-142979D01*
G01Y-131779D02*
X336439Y-131579D01*
Y-131179D01*
X336639Y-130979D01*
X336839Y-131179D01*
Y-131579D01*
X336639Y-131779D01*
G01X342039Y-142979D02*
Y-132779D01*
X342239Y-131779D01*
X342639Y-131179D01*
X343239Y-130979D01*
X343839Y-131379D01*
X344139Y-132379D01*
G01X342939Y-135779D02*
X340939D01*
G01X348039Y-142979D02*
Y-132779D01*
X348239Y-131779D01*
X348639Y-131179D01*
X349239Y-130979D01*
X349839Y-131379D01*
X350139Y-132379D01*
G01X348939Y-135779D02*
X346939D01*
G01X353139Y-137579D02*
X356339D01*
X356039Y-136179D01*
X355539Y-135379D01*
X354839Y-134979D01*
X354139Y-135179D01*
X353539Y-135779D01*
X353139Y-137179D01*
X352939Y-138379D01*
Y-139579D01*
X353139Y-140779D01*
X353639Y-141979D01*
X354239Y-142779D01*
X354939Y-142979D01*
X355639Y-142579D01*
X356339Y-141379D01*
G01X359239Y-142979D02*
Y-134979D01*
G01Y-136579D02*
X359739Y-135779D01*
X360239Y-135179D01*
X360939Y-134979D01*
X361439Y-135179D01*
X362039Y-135779D01*
G01X365139Y-137579D02*
X368339D01*
X368039Y-136179D01*
X367539Y-135379D01*
X366839Y-134979D01*
X366139Y-135179D01*
X365539Y-135779D01*
X365139Y-137179D01*
X364939Y-138379D01*
Y-139579D01*
X365139Y-140779D01*
X365639Y-141979D01*
X366239Y-142779D01*
X366939Y-142979D01*
X367639Y-142579D01*
X368339Y-141379D01*
G01X370939Y-142979D02*
Y-134979D01*
G01Y-136979D02*
X371339Y-135979D01*
X371939Y-135179D01*
X372739Y-134979D01*
X373439Y-135179D01*
X374039Y-135979D01*
X374339Y-137379D01*
Y-142979D01*
G01X378639Y-130979D02*
Y-142979D01*
G01X377239Y-134979D02*
X380039D01*
G01X384639D02*
Y-142979D01*
G01Y-131779D02*
X384439Y-131579D01*
Y-131179D01*
X384639Y-130979D01*
X384839Y-131179D01*
Y-131579D01*
X384639Y-131779D01*
G01X392439Y-142979D02*
Y-134979D01*
G01Y-136379D02*
X392039Y-135579D01*
X391439Y-135179D01*
X390739Y-134979D01*
X390039Y-135379D01*
X389439Y-136179D01*
X389039Y-137379D01*
X388839Y-138979D01*
X389039Y-140579D01*
X389439Y-141779D01*
X390039Y-142579D01*
X390739Y-142979D01*
X391439Y-142779D01*
X392039Y-142179D01*
X392439Y-141379D01*
G01X396639Y-142979D02*
Y-130979D01*
G01X408639D02*
Y-142979D01*
G01X407239Y-134979D02*
X410039D01*
G01X413239Y-142979D02*
Y-134979D01*
G01Y-136579D02*
X413739Y-135779D01*
X414239Y-135179D01*
X414939Y-134979D01*
X415439Y-135179D01*
X416039Y-135779D01*
G01X422439Y-142979D02*
Y-134979D01*
G01Y-136379D02*
X422039Y-135579D01*
X421439Y-135179D01*
X420739Y-134979D01*
X420039Y-135379D01*
X419439Y-136179D01*
X419039Y-137379D01*
X418839Y-138979D01*
X419039Y-140579D01*
X419439Y-141779D01*
X420039Y-142579D01*
X420739Y-142979D01*
X421439Y-142779D01*
X422039Y-142179D01*
X422439Y-141379D01*
G01X428239Y-135979D02*
X427539Y-135179D01*
X426939Y-134979D01*
X426139Y-135379D01*
X425539Y-136179D01*
X425139Y-137579D01*
X425039Y-138979D01*
X425139Y-140379D01*
X425539Y-141579D01*
X426139Y-142579D01*
X426939Y-142979D01*
X427639Y-142579D01*
X428239Y-141779D01*
G01X431139Y-137579D02*
X434339D01*
X434039Y-136179D01*
X433539Y-135379D01*
X432839Y-134979D01*
X432139Y-135179D01*
X431539Y-135779D01*
X431139Y-137179D01*
X430939Y-138379D01*
Y-139579D01*
X431139Y-140779D01*
X431639Y-141979D01*
X432239Y-142779D01*
X432939Y-142979D01*
X433639Y-142579D01*
X434339Y-141379D01*
G01X437139Y-141579D02*
X437639Y-142379D01*
X438339Y-142979D01*
X438939D01*
X439539Y-142579D01*
X439939Y-141979D01*
X440139Y-141179D01*
X440039Y-139979D01*
X439639Y-139379D01*
X437839Y-138179D01*
X437439Y-136779D01*
X437639Y-135779D01*
X438039Y-135179D01*
X438639Y-134979D01*
X439239Y-135179D01*
X439839Y-135779D01*
G01X450639Y-134979D02*
Y-142979D01*
G01Y-131779D02*
X450439Y-131579D01*
Y-131179D01*
X450639Y-130979D01*
X450839Y-131179D01*
Y-131579D01*
X450639Y-131779D01*
G01X454939Y-142979D02*
Y-134979D01*
G01Y-136979D02*
X455339Y-135979D01*
X455939Y-135179D01*
X456739Y-134979D01*
X457439Y-135179D01*
X458039Y-135979D01*
X458339Y-137379D01*
Y-142979D01*
G01X468639D02*
Y-130979D01*
G01X476439Y-142979D02*
Y-134979D01*
G01Y-136379D02*
X476039Y-135579D01*
X475439Y-135179D01*
X474739Y-134979D01*
X474039Y-135379D01*
X473439Y-136179D01*
X473039Y-137379D01*
X472839Y-138979D01*
X473039Y-140579D01*
X473439Y-141779D01*
X474039Y-142579D01*
X474739Y-142979D01*
X475439Y-142779D01*
X476039Y-142179D01*
X476439Y-141379D01*
G01X478539Y-146579D02*
X479139Y-146979D01*
X479939Y-146579D01*
X480439Y-145779D01*
X480839Y-144779D01*
X481439Y-141579D01*
X482739Y-134979D01*
G01X479539D02*
X481439Y-141579D01*
G01X485139Y-137579D02*
X488339D01*
X488039Y-136179D01*
X487539Y-135379D01*
X486839Y-134979D01*
X486139Y-135179D01*
X485539Y-135779D01*
X485139Y-137179D01*
X484939Y-138379D01*
Y-139579D01*
X485139Y-140779D01*
X485639Y-141979D01*
X486239Y-142779D01*
X486939Y-142979D01*
X487639Y-142579D01*
X488339Y-141379D01*
G01X491239Y-142979D02*
Y-134979D01*
G01Y-136579D02*
X491739Y-135779D01*
X492239Y-135179D01*
X492939Y-134979D01*
X493439Y-135179D01*
X494039Y-135779D01*
G01X502639Y-130979D02*
Y-142979D01*
X506639D01*
G01X508739Y-137979D02*
X509439Y-136579D01*
X510039Y-135779D01*
X510839Y-135379D01*
X511539Y-135779D01*
X512039Y-136579D01*
X512439Y-137779D01*
X512539Y-139179D01*
X512439Y-140379D01*
X512039Y-141579D01*
X511439Y-142579D01*
X510739Y-142979D01*
X509939Y-142579D01*
X509239Y-141379D01*
X508839Y-139579D01*
X508739Y-137579D01*
X508939Y-134979D01*
X509239Y-133579D01*
X509739Y-132179D01*
X510439Y-131179D01*
X511139Y-130979D01*
X511839Y-131379D01*
X512339Y-132379D01*
G01X36516Y309567D02*
G02X22539I-6989J0D01*
G02X36516I6989J0D01*
G01Y1029528D02*
G02X22539I-6989J0D01*
G02X36516I6989J0D01*
G01X137795Y17717D02*
G02X122047I-7874J0D01*
G02X137795I7874J0D01*
G01X278642Y267717D02*
G02X264665I-6989J0D01*
G02X278642I6988J0D01*
G01Y673228D02*
G02X264665I-6989J0D01*
G02X278642I6988J0D01*
G01Y1078740D02*
G02X264665I-6989J0D01*
G02X278642I6988J0D01*
G01Y1484252D02*
G02X264665I-6989J0D01*
G02X278642I6988J0D01*
G01Y1889764D02*
G02X264665I-6989J0D01*
G02X278642I6988J0D01*
G01X1001083Y149606D02*
G02X987106I-6989J0D01*
G02X1001083I6988J0D01*
G01Y673228D02*
G02X987106I-6989J0D01*
G02X1001083I6988J0D01*
G01Y1068898D02*
G02X987106I-6989J0D01*
G02X1001083I6988J0D01*
G01X1001969Y1889764D02*
G02X986220I-7875J0D01*
G02X1001969I7874J0D01*
G01X1012008Y1416024D02*
G02X1026575I7284J0D01*
G02X1012008I-7283J0D01*
G01Y1694213D02*
G02X1026575I7284J0D01*
G02X1012008I-7283J0D01*
M02*
